# BASEBOARD_FAB2 (Tioga Pass) — schematic netlist excerpt (pin names and nets, part order shuffled) for the footprints in the layout excerpt that follows; sources: Cadence DE-HDL packaged netlist, KiCad conversion of Wiwynn_Tioga_Pass_MB.brd

J1B1  SCONN288_H44441004  SCONN  pkg PIP  page 83
  \12v\(1)  = P12V_NVDIMM_KLM
  VSS(93)  = GND
  DQ(4)  = M_K_DQ<5>
  VSS(92)  = GND
  DQ(0)  = M_K_DQ<1>
  VSS(91)  = GND
  DQS9P  = M_K_DQS_DP<9>
  DQS9N  = M_K_DQS_DN<9>
  VSS(90)  = GND
  DQ(6)  = M_K_DQ<7>
  VSS(89)  = GND
  DQ(2)  = M_K_DQ<3>
  VSS(88)  = GND
  DQ(12)  = M_K_DQ<13>
  VSS(87)  = GND
  DQ(8)  = M_K_DQ<9>
  VSS(86)  = GND
  DQS10P  = M_K_DQS_DP<10>
  DQS10N  = M_K_DQS_DN<10>
  VSS(85)  = GND
  DQ(14)  = M_K_DQ<15>
  VSS(84)  = GND
  DQ(10)  = M_K_DQ<11>
  VSS(83)  = GND
  DQ(20)  = M_K_DQ<21>
  VSS(82)  = GND
  DQ(16)  = M_K_DQ<17>
  VSS(81)  = GND
  DQS11P  = M_K_DQS_DP<11>
  DQS11N  = M_K_DQS_DN<11>
  VSS(80)  = GND
  DQ(22)  = M_K_DQ<23>
  VSS(79)  = GND
  DQ(18)  = M_K_DQ<19>
  VSS(78)  = GND
  DQ(28)  = M_K_DQ<29>
  VSS(77)  = GND
  DQ(24)  = M_K_DQ<25>
  VSS(76)  = GND
  DQS12P  = M_K_DQS_DP<12>
  DQS12N  = M_K_DQS_DN<12>
  VSS(75)  = GND
  DQ(30)  = M_K_DQ<31>
  VSS(74)  = GND
  DQ(26)  = M_K_DQ<27>
  VSS(73)  = GND
  CB(4)  = M_K_ECC<5>
  VSS(72)  = GND
  CB(0)  = M_K_ECC<1>
  VSS(71)  = GND
  DQS17P  = M_K_DQS_DP<17>
  DQS17N  = M_K_DQS_DN<17>
  VSS(70)  = GND
  CB(6)  = M_K_ECC<7>
  VSS(69)  = GND
  CB(2)  = M_K_ECC<3>
  VSS(68)  = GND
  RESET_N  = M_KLM_RST_N
  VDD(25)  = PVDDQ_KLM
  CKE(0)  = M_K_CKE<0>
  VDD(24)  = PVDDQ_KLM
  ACT_N  = M_K_ACT_N
  BG(0)  = M_K_BG<0>
  VDD(23)  = PVDDQ_KLM
  A12  = M_K_MA<12>
  A9  = M_K_MA<9>
  VDD(22)  = PVDDQ_KLM
  A8  = M_K_MA<8>
  A6  = M_K_MA<6>
  VDD(21)  = PVDDQ_KLM
  A3  = M_K_MA<3>
  A1  = M_K_MA<1>
  VDD(20)  = PVDDQ_KLM
  CK0P  = M_K_CLK_DP<0>
  CK0N  = M_K_CLK_DN<0>
  VDD(19)  = PVDDQ_KLM
  VTT(1)  = PVTT_KLM
  EVENT_N  = FM_DIMM_EVENT_COD_N
  A0  = M_K_MA<0>
  VDD(18)  = PVDDQ_KLM
  BA(0)  = M_K_BA<0>
  A16_RAS_N  = M_K_MA<16>
  VDD(17)  = PVDDQ_KLM
  S0_N  = M_K_CS_N<0>
  VDD(16)  = PVDDQ_KLM
  A15_CAS_N  = M_K_MA<15>
  ODT(0)  = M_K_ODT<0>
  VDD(15)  = PVDDQ_KLM
  S1_N  = M_K_CS_N<1>
  VDD(14)  = PVDDQ_KLM
  ODT(1)  = M_K_ODT<1>
  VDD(13)  = PVDDQ_KLM
  S2_N_C(0)  = M_K_CS_N<2>
  VSS(67)  = GND
  DQ(36)  = M_K_DQ<37>
  VSS(66)  = GND
  DQ(32)  = M_K_DQ<33>
  VSS(65)  = GND
  DQS13P  = M_K_DQS_DP<13>
  DQS13N  = M_K_DQS_DN<13>
  VSS(64)  = GND
  DQ(38)  = M_K_DQ<39>
  VSS(63)  = GND
  DQ(34)  = M_K_DQ<35>
  VSS(62)  = GND
  DQ(44)  = M_K_DQ<45>
  VSS(61)  = GND
  DQ(40)  = M_K_DQ<41>
  VSS(60)  = GND
  DQS14P  = M_K_DQS_DP<14>
  DQS14N  = M_K_DQS_DN<14>
  VSS(59)  = GND
  DQ(46)  = M_K_DQ<47>
  VSS(58)  = GND
  DQ(42)  = M_K_DQ<43>
  VSS(57)  = GND
  DQ(52)  = M_K_DQ<53>
  VSS(56)  = GND
  DQ(48)  = M_K_DQ<49>
  VSS(55)  = GND
  DQS15P  = M_K_DQS_DP<15>
  DQS15N  = M_K_DQS_DN<15>
  VSS(54)  = GND
  DQ(54)  = M_K_DQ<55>
  VSS(53)  = GND
  DQ(50)  = M_K_DQ<51>
  VSS(52)  = GND
  DQ(60)  = M_K_DQ<61>
  VSS(51)  = GND
  DQ(56)  = M_K_DQ<57>
  VSS(50)  = GND
  DQS16P  = M_K_DQS_DP<16>
  DQS16N  = M_K_DQS_DN<16>
  VSS(49)  = GND
  DQ(62)  = M_K_DQ<63>
  VSS(48)  = GND
  DQ(58)  = M_K_DQ<59>
  VSS(47)  = GND
  SA(0)  = GND
  SA(1)  = GND
  SCL  = SMB_DDR_KLM_VPP_SCL
  VPP(4)  = PVPP_KLM
  VPP(3)  = PVPP_KLM
  RFU(2)  = TP_CH_K_DIMM_K0_RFU_2
  \12v\(0)  = P12V_NVDIMM_KLM
  VREFCA  = M_K_VREF
  VSS(46)  = GND
  DQ(5)  = M_K_DQ<4>
  VSS(45)  = GND
  DQ(1)  = M_K_DQ<0>
  VSS(44)  = GND
  DQS0N  = M_K_DQS_DN<0>
  DQS0P  = M_K_DQS_DP<0>
  VSS(43)  = GND
  DQ(7)  = M_K_DQ<6>
  VSS(42)  = GND
  DQ(3)  = M_K_DQ<2>
  VSS(41)  = GND
  DQ(13)  = M_K_DQ<12>
  VSS(40)  = GND
  DQ(9)  = M_K_DQ<8>
  VSS(39)  = GND
  DQS1N  = M_K_DQS_DN<1>
  DQS1P  = M_K_DQS_DP<1>
  VSS(38)  = GND
  DQ(15)  = M_K_DQ<14>
  VSS(37)  = GND
  DQ(11)  = M_K_DQ<10>
  VSS(36)  = GND
  DQ(21)  = M_K_DQ<20>
  VSS(35)  = GND
  DQ(17)  = M_K_DQ<16>
  VSS(34)  = GND
  DQS2N  = M_K_DQS_DN<2>
  DQS2P  = M_K_DQS_DP<2>
  VSS(33)  = GND
  DQ(23)  = M_K_DQ<22>
  VSS(32)  = GND
  DQ(19)  = M_K_DQ<18>
  VSS(31)  = GND
  DQ(29)  = M_K_DQ<28>
  VSS(30)  = GND
  DQ(25)  = M_K_DQ<24>
  VSS(29)  = GND
  DQS3N  = M_K_DQS_DN<3>
  DQS3P  = M_K_DQS_DP<3>
  VSS(28)  = GND
  DQ(31)  = M_K_DQ<30>
  VSS(27)  = GND
  DQ(27)  = M_K_DQ<26>
  VSS(26)  = GND
  CB(5)  = M_K_ECC<4>
  VSS(25)  = GND
  CB(1)  = M_K_ECC<0>
  VSS(24)  = GND
  DQS8N  = M_K_DQS_DN<8>
  DQS8P  = M_K_DQS_DP<8>
  VSS(23)  = GND
  CB(7)  = M_K_ECC<6>
  VSS(22)  = GND
  CB(3)  = M_K_ECC<2>
  VSS(21)  = GND
  CKE(1)  = M_K_CKE<1>
  VDD(12)  = PVDDQ_KLM
  RFU(0)  = TP_CH_K_DIMM_K0_RFU_0
  VDD(11)  = PVDDQ_KLM
  BG(1)  = M_K_BG<1>
  ALERT_N  = M_K_ALERT_N
  VDD(10)  = PVDDQ_KLM
  A11  = M_K_MA<11>
  A7  = M_K_MA<7>
  VDD(9)  = PVDDQ_KLM
  A5  = M_K_MA<5>
  A4  = M_K_MA<4>
  VDD(8)  = PVDDQ_KLM
  A2  = M_K_MA<2>
  VDD(7)  = PVDDQ_KLM
  CK1P  = M_K_CLK_DP<1>
  CK1N  = M_K_CLK_DN<1>
  VDD(6)  = PVDDQ_KLM
  VTT(0)  = PVTT_KLM
  PAR  = M_K_PAR
  VDD(5)  = PVDDQ_KLM
  BA(1)  = M_K_BA<1>
  A10  = M_K_MA<10>
  VDD(4)  = PVDDQ_KLM
  RFU(1)  = TP_CH_K_DIMM_K0_RFU_1
  A14_WE_N  = M_K_MA<14>
  VDD(3)  = PVDDQ_KLM
  SAVE_N_NC  = FM_ADR_COMPLETE_KLM_N
  VDD(2)  = PVDDQ_KLM
  A13  = M_K_MA<13>
  VDD(1)  = PVDDQ_KLM
  A17  = M_K_MA<17>
  C(2)  = M_K_C<2>
  VDD(0)  = PVDDQ_KLM
  S3_N_C(1)  = M_K_CS_N<3>
  SA(2)  = GND
  VSS(20)  = GND
  DQ(37)  = M_K_DQ<36>
  VSS(19)  = GND
  DQ(33)  = M_K_DQ<32>
  VSS(18)  = GND
  DQS4N  = M_K_DQS_DN<4>
  DQS4P  = M_K_DQS_DP<4>
  VSS(17)  = GND
  DQ(39)  = M_K_DQ<38>
  VSS(16)  = GND
  DQ(35)  = M_K_DQ<34>
  VSS(15)  = GND
  DQ(45)  = M_K_DQ<44>
  VSS(14)  = GND
  DQ(41)  = M_K_DQ<40>
  VSS(13)  = GND
  DQS5N  = M_K_DQS_DN<5>
  DQS5P  = M_K_DQS_DP<5>
  VSS(12)  = GND
  DQ(47)  = M_K_DQ<46>
  VSS(11)  = GND
  DQ(43)  = M_K_DQ<42>
  VSS(10)  = GND
  DQ(53)  = M_K_DQ<52>
  VSS(9)  = GND
  DQ(49)  = M_K_DQ<48>
  VSS(8)  = GND
  DQS6N  = M_K_DQS_DN<6>
  DQS6P  = M_K_DQS_DP<6>
  VSS(7)  = GND
  DQ(55)  = M_K_DQ<54>
  VSS(6)  = GND
  DQ(51)  = M_K_DQ<50>
  VSS(5)  = GND
  DQ(61)  = M_K_DQ<60>
  VSS(4)  = GND
  DQ(57)  = M_K_DQ<56>
  VSS(3)  = GND
  DQS7N  = M_K_DQS_DN<7>
  DQS7P  = M_K_DQS_DP<7>
  VSS(2)  = GND
  DQ(63)  = M_K_DQ<62>
  VSS(1)  = GND
  DQ(59)  = M_K_DQ<58>
  VSS(0)  = GND
  VDDSPD  = PVPP_KLM
  SDA  = SMB_DDR_KLM_VPP_SDA
  VPP(1)  = PVPP_KLM
  VPP(0)  = PVPP_KLM
  VPP(2)  = PVPP_KLM

(kicad_pcb
	(version 20260206)
	(generator "pcbnew")
	(generator_version "10.0")
	(general
		(thickness 1.6)
		(legacy_teardrops no)
	)
	(paper "A4")
	(title_block
		(title "Wiwynn_Tioga_Pass_MB.brd")
		(comment 1 "Tioga Pass / footprint 320 of 4770 (J1B1), pads 1-51 of 291")
	)
	(layers
		(0 "F.Cu" signal "TOP")
		(4 "In1.Cu" signal "L2GND")
		(6 "In2.Cu" signal "L3")
		(8 "In3.Cu" signal "L4GND")
		(10 "In4.Cu" signal "L5")
		(12 "In5.Cu" signal "L6GND")
		(14 "In6.Cu" signal "L7VCC")
		(16 "In7.Cu" signal "L8VCC")
		(18 "In8.Cu" signal "L9GND")
		(20 "In9.Cu" signal "L10")
		(22 "In10.Cu" signal "L11GND")
		(24 "In11.Cu" signal "L12")
		(26 "In12.Cu" signal "L13GND")
		(2 "B.Cu" signal "BOTTOM")
		(9 "F.Adhes" user "F.Adhesive")
		(11 "B.Adhes" user "B.Adhesive")
		(13 "F.Paste" user "Package Geometry/Pastemask Top")
		(15 "B.Paste" user "Package Geometry/Pastemask Bottom")
		(5 "F.SilkS" user "Ref Des/Silkscreen Top")
		(7 "B.SilkS" user "Ref Des/Silkscreen Bottom")
		(1 "F.Mask" user "Board Geometry/Soldermask Top")
		(3 "B.Mask" user "Board Geometry/Soldermask Bottom")
		(17 "Dwgs.User" user "User.Drawings")
		(19 "Cmts.User" user "User.Comments")
		(21 "Eco1.User" user "User.Eco1")
		(23 "Eco2.User" user "User.Eco2")
		(25 "Edge.Cuts" user "Board Geometry/Outline")
		(27 "Margin" user)
		(31 "F.CrtYd" user "Package Geometry/Place Bound Top")
		(29 "B.CrtYd" user "Package Geometry/Place Bound Bottom")
		(35 "F.Fab" user "Ref Des/Assembly Top")
		(33 "B.Fab" user "Ref Des/Assembly Bottom")
	)
	(footprint ""
		(layer "F.Cu")
		(at 29.699458 -133.0706 90)
		(property "Reference" "J1B1"
			(at -4.960112 38.372542 0)
			(unlocked yes)
			(layer "F.SilkS")
			(effects
				(font
					(size 0.7874 0.5842)
					(thickness 0.1524)
				)
				(justify left)
			)
		)
		(property "Value" ""
			(at 0 0 90)
			(layer "F.Fab")
			(effects
				(font
					(size 1.27 1.27)
				)
			)
		)
		(duplicate_pad_numbers_are_jumpers no)
		(pad "" thru_hole circle
			(at 2.29997 -5.649976 90)
			(size 2.8194 2.8194)
			(drill 2.4384)
			(layers "*.Cu" "*.Mask")
			(remove_unused_layers no)
			(clearance 0.127)
			(thermal_gap 0.127)
		)
		(pad "" thru_hole oval
			(at 2.29997 68.90004 90)
			(size 2.8194 1.5748)
			(drill oval 2.4384 1.1938)
			(layers "*.Cu" "*.Mask")
			(remove_unused_layers no)
			(clearance 0.127)
			(thermal_gap 0.127)
		)
		(pad "" thru_hole circle
			(at 2.29997 132.299964 90)
			(size 2.8194 2.8194)
			(drill 2.4384)
			(layers "*.Cu" "*.Mask")
			(remove_unused_layers no)
			(clearance 0.127)
			(thermal_gap 0.127)
		)
		(pad "1" smd rect
			(at 0 0 90)
			(size 1.8034 0.508)
			(layers "F.Cu" "F.Mask" "F.Paste")
			(net "P12V_NVDIMM_KLM")
		)
		(pad "2" smd rect
			(at 0 0.849884 90)
			(size 1.8034 0.508)
			(layers "F.Cu" "F.Mask" "F.Paste")
			(net "GND")
		)
		(pad "3" smd rect
			(at 0 1.700022 90)
			(size 1.8034 0.508)
			(layers "F.Cu" "F.Mask" "F.Paste")
			(net "M_K_DQ<5>")
		)
		(pad "4" smd rect
			(at 0 2.549906 90)
			(size 1.8034 0.508)
			(layers "F.Cu" "F.Mask" "F.Paste")
			(net "GND")
		)
		(pad "5" smd rect
			(at 0 3.400044 90)
			(size 1.8034 0.508)
			(layers "F.Cu" "F.Mask" "F.Paste")
			(net "M_K_DQ<1>")
		)
		(pad "6" smd rect
			(at 0 4.249928 90)
			(size 1.8034 0.508)
			(layers "F.Cu" "F.Mask" "F.Paste")
			(net "GND")
		)
		(pad "7" smd rect
			(at 0 5.100066 90)
			(size 1.8034 0.508)
			(layers "F.Cu" "F.Mask" "F.Paste")
			(net "M_K_DQS_DP<9>")
		)
		(pad "8" smd rect
			(at 0 5.94995 90)
			(size 1.8034 0.508)
			(layers "F.Cu" "F.Mask" "F.Paste")
			(net "M_K_DQS_DN<9>")
		)
		(pad "9" smd rect
			(at 0 6.800088 90)
			(size 1.8034 0.508)
			(layers "F.Cu" "F.Mask" "F.Paste")
			(net "GND")
		)
		(pad "10" smd rect
			(at 0 7.649972 90)
			(size 1.8034 0.508)
			(layers "F.Cu" "F.Mask" "F.Paste")
			(net "M_K_DQ<7>")
		)
		(pad "11" smd rect
			(at 0 8.50011 90)
			(size 1.8034 0.508)
			(layers "F.Cu" "F.Mask" "F.Paste")
			(net "GND")
		)
		(pad "12" smd rect
			(at 0 9.349994 90)
			(size 1.8034 0.508)
			(layers "F.Cu" "F.Mask" "F.Paste")
			(net "M_K_DQ<3>")
		)
		(pad "13" smd rect
			(at 0 10.199878 90)
			(size 1.8034 0.508)
			(layers "F.Cu" "F.Mask" "F.Paste")
			(net "GND")
		)
		(pad "14" smd rect
			(at 0 11.050016 90)
			(size 1.8034 0.508)
			(layers "F.Cu" "F.Mask" "F.Paste")
			(net "M_K_DQ<13>")
		)
		(pad "15" smd rect
			(at 0 11.8999 90)
			(size 1.8034 0.508)
			(layers "F.Cu" "F.Mask" "F.Paste")
			(net "GND")
		)
		(pad "16" smd rect
			(at 0 12.750038 90)
			(size 1.8034 0.508)
			(layers "F.Cu" "F.Mask" "F.Paste")
			(net "M_K_DQ<9>")
		)
		(pad "17" smd rect
			(at 0 13.599922 90)
			(size 1.8034 0.508)
			(layers "F.Cu" "F.Mask" "F.Paste")
			(net "GND")
		)
		(pad "18" smd rect
			(at 0 14.45006 90)
			(size 1.8034 0.508)
			(layers "F.Cu" "F.Mask" "F.Paste")
			(net "M_K_DQS_DP<10>")
		)
		(pad "19" smd rect
			(at 0 15.299944 90)
			(size 1.8034 0.508)
			(layers "F.Cu" "F.Mask" "F.Paste")
			(net "M_K_DQS_DN<10>")
		)
		(pad "20" smd rect
			(at 0 16.150082 90)
			(size 1.8034 0.508)
			(layers "F.Cu" "F.Mask" "F.Paste")
			(net "GND")
		)
		(pad "21" smd rect
			(at 0 16.999966 90)
			(size 1.8034 0.508)
			(layers "F.Cu" "F.Mask" "F.Paste")
			(net "M_K_DQ<15>")
		)
		(pad "22" smd rect
			(at 0 17.850104 90)
			(size 1.8034 0.508)
			(layers "F.Cu" "F.Mask" "F.Paste")
			(net "GND")
		)
		(pad "23" smd rect
			(at 0 18.699988 90)
			(size 1.8034 0.508)
			(layers "F.Cu" "F.Mask" "F.Paste")
			(net "M_K_DQ<11>")
		)
		(pad "24" smd rect
			(at 0 19.550126 90)
			(size 1.8034 0.508)
			(layers "F.Cu" "F.Mask" "F.Paste")
			(net "GND")
		)
		(pad "25" smd rect
			(at 0 20.40001 90)
			(size 1.8034 0.508)
			(layers "F.Cu" "F.Mask" "F.Paste")
			(net "M_K_DQ<21>")
		)
		(pad "26" smd rect
			(at 0 21.249894 90)
			(size 1.8034 0.508)
			(layers "F.Cu" "F.Mask" "F.Paste")
			(net "GND")
		)
		(pad "27" smd rect
			(at 0 22.100032 90)
			(size 1.8034 0.508)
			(layers "F.Cu" "F.Mask" "F.Paste")
			(net "M_K_DQ<17>")
		)
		(pad "28" smd rect
			(at 0 22.949916 90)
			(size 1.8034 0.508)
			(layers "F.Cu" "F.Mask" "F.Paste")
			(net "GND")
		)
		(pad "29" smd rect
			(at 0 23.800054 90)
			(size 1.8034 0.508)
			(layers "F.Cu" "F.Mask" "F.Paste")
			(net "M_K_DQS_DP<11>")
		)
		(pad "30" smd rect
			(at 0 24.649938 90)
			(size 1.8034 0.508)
			(layers "F.Cu" "F.Mask" "F.Paste")
			(net "M_K_DQS_DN<11>")
		)
		(pad "31" smd rect
			(at 0 25.500076 90)
			(size 1.8034 0.508)
			(layers "F.Cu" "F.Mask" "F.Paste")
			(net "GND")
		)
		(pad "32" smd rect
			(at 0 26.34996 90)
			(size 1.8034 0.508)
			(layers "F.Cu" "F.Mask" "F.Paste")
			(net "M_K_DQ<23>")
		)
		(pad "33" smd rect
			(at 0 27.200098 90)
			(size 1.8034 0.508)
			(layers "F.Cu" "F.Mask" "F.Paste")
			(net "GND")
		)
		(pad "34" smd rect
			(at 0 28.049982 90)
			(size 1.8034 0.508)
			(layers "F.Cu" "F.Mask" "F.Paste")
			(net "M_K_DQ<19>")
		)
		(pad "35" smd rect
			(at 0 28.90012 90)
			(size 1.8034 0.508)
			(layers "F.Cu" "F.Mask" "F.Paste")
			(net "GND")
		)
		(pad "36" smd rect
			(at 0 29.750004 90)
			(size 1.8034 0.508)
			(layers "F.Cu" "F.Mask" "F.Paste")
			(net "M_K_DQ<29>")
		)
		(pad "37" smd rect
			(at 0 30.599888 90)
			(size 1.8034 0.508)
			(layers "F.Cu" "F.Mask" "F.Paste")
			(net "GND")
		)
		(pad "38" smd rect
			(at 0 31.450026 90)
			(size 1.8034 0.508)
			(layers "F.Cu" "F.Mask" "F.Paste")
			(net "M_K_DQ<25>")
		)
		(pad "39" smd rect
			(at 0 32.29991 90)
			(size 1.8034 0.508)
			(layers "F.Cu" "F.Mask" "F.Paste")
			(net "GND")
		)
		(pad "40" smd rect
			(at 0 33.150048 90)
			(size 1.8034 0.508)
			(layers "F.Cu" "F.Mask" "F.Paste")
			(net "M_K_DQS_DP<12>")
		)
		(pad "41" smd rect
			(at 0 33.999932 90)
			(size 1.8034 0.508)
			(layers "F.Cu" "F.Mask" "F.Paste")
			(net "M_K_DQS_DN<12>")
		)
		(pad "42" smd rect
			(at 0 34.85007 90)
			(size 1.8034 0.508)
			(layers "F.Cu" "F.Mask" "F.Paste")
			(net "GND")
		)
		(pad "43" smd rect
			(at 0 35.699954 90)
			(size 1.8034 0.508)
			(layers "F.Cu" "F.Mask" "F.Paste")
			(net "M_K_DQ<31>")
		)
		(pad "44" smd rect
			(at 0 36.550092 90)
			(size 1.8034 0.508)
			(layers "F.Cu" "F.Mask" "F.Paste")
			(net "GND")
		)
		(pad "45" smd rect
			(at 0 37.399976 90)
			(size 1.8034 0.508)
			(layers "F.Cu" "F.Mask" "F.Paste")
			(net "M_K_DQ<27>")
		)
		(pad "46" smd rect
			(at 0 38.250114 90)
			(size 1.8034 0.508)
			(layers "F.Cu" "F.Mask" "F.Paste")
			(net "GND")
		)
		(pad "47" smd rect
			(at 0 39.099998 90)
			(size 1.8034 0.508)
			(layers "F.Cu" "F.Mask" "F.Paste")
			(net "M_K_ECC<5>")
		)
		(pad "48" smd rect
			(at 0 39.949882 90)
			(size 1.8034 0.508)
			(layers "F.Cu" "F.Mask" "F.Paste")
			(net "GND")
		)
	)
)
